# T6G (Grand Teton) — schematic netlist excerpt (pin names and nets, part order shuffled) for the footprints in the layout excerpt that follows; sources: Cadence DE-HDL packaged netlist, KiCad conversion of 04192023_DAF0TMB3IC0_F0TG_MB_C_brd_V02_OCP.brd

R1401  Q_RES  4.7K 5% CHIP  pkg 0201LF  page 298 : A = JTAG_TCK_RT_CPU0_P2 ; B = GND
C117  Q_CAP  22UF 4V 20% X6S  pkg C0402  page 323 : A = P1V8_CPU1_RT0_1A ; B = GND
R6218  Q_RES  10K 1% EMPTY  pkg 0402LF  page 176 : A = P3V3_AUX ; B = USB_CPU0_ADD_A1

(kicad_pcb
	(version 20260206)
	(generator "pcbnew")
	(generator_version "10.0")
	(general
		(thickness 1.6)
		(legacy_teardrops no)
	)
	(paper "A4")
	(title_block
		(title "04192023_DAF0TMB3IC0_F0TG_MB_C_brd_V02_OCP.brd")
		(comment 1 "Grand Teton / footprints 2251-2253 of 8354")
	)
	(layers
		(0 "F.Cu" signal "TOP")
		(4 "In1.Cu" signal "GND")
		(6 "In2.Cu" signal "IN1")
		(8 "In3.Cu" signal "GND1")
		(10 "In4.Cu" signal "IN2")
		(12 "In5.Cu" signal "GND2")
		(14 "In6.Cu" signal "IN3")
		(16 "In7.Cu" signal "GND3")
		(18 "In8.Cu" signal "VCC")
		(20 "In9.Cu" signal "VCC1")
		(22 "In10.Cu" signal "GND4")
		(24 "In11.Cu" signal "IN4")
		(26 "In12.Cu" signal "GND5")
		(28 "In13.Cu" signal "IN5")
		(30 "In14.Cu" signal "GND6")
		(32 "In15.Cu" signal "IN6")
		(34 "In16.Cu" signal "GND7")
		(2 "B.Cu" signal "BOTTOM")
		(9 "F.Adhes" user "F.Adhesive")
		(11 "B.Adhes" user "B.Adhesive")
		(13 "F.Paste" user "Package Geometry/Pastemask Top")
		(15 "B.Paste" user "Package Geometry/Pastemask Bottom")
		(5 "F.SilkS" user "Ref Des/Silkscreen Top")
		(7 "B.SilkS" user "Ref Des/Silkscreen Bottom")
		(1 "F.Mask" user "Board Geometry/Soldermask Top")
		(3 "B.Mask" user "Board Geometry/Soldermask Bottom")
		(17 "Dwgs.User" user "User.Drawings")
		(19 "Cmts.User" user "User.Comments")
		(21 "Eco1.User" user "User.Eco1")
		(23 "Eco2.User" user "User.Eco2")
		(25 "Edge.Cuts" user "Board Geometry/Outline")
		(27 "Margin" user)
		(31 "F.CrtYd" user "Package Geometry/Place Bound Top")
		(29 "B.CrtYd" user "Package Geometry/Place Bound Bottom")
		(35 "F.Fab" user "Ref Des/Assembly Top")
		(33 "B.Fab" user "Ref Des/Assembly Bottom")
	)
	(footprint ""
		(layer "F.Cu")
		(at 436.052722 -409.68676)
		(property "Reference" "R1401"
			(at 0 0 0)
			(layer "F.SilkS")
			(hide yes)
			(effects
				(font
					(size 1.27 1.27)
				)
			)
		)
		(property "Value" ""
			(at 0 0 0)
			(layer "F.Fab")
			(effects
				(font
					(size 1.27 1.27)
				)
			)
		)
		(duplicate_pad_numbers_are_jumpers no)
		(fp_line
			(start -0.32512 -0.175006)
			(end 0.32512 -0.175006)
			(stroke
				(width 0.1)
				(type default)
			)
			(layer "F.Fab")
		)
		(fp_line
			(start -0.32512 0.175006)
			(end -0.32512 -0.175006)
			(stroke
				(width 0.1)
				(type default)
			)
			(layer "F.Fab")
		)
		(fp_line
			(start 0.32512 -0.175006)
			(end 0.32512 0.175006)
			(stroke
				(width 0.1)
				(type default)
			)
			(layer "F.Fab")
		)
		(fp_line
			(start 0.32512 0.175006)
			(end -0.32512 0.175006)
			(stroke
				(width 0.1)
				(type default)
			)
			(layer "F.Fab")
		)
		(pad "1" smd rect
			(at -0.2667 0)
			(size 0.3048 0.381)
			(layers "F.Cu" "F.Mask" "F.Paste")
			(net "JTAG_TCK_RT_CPU0_P2")
		)
		(pad "2" smd rect
			(at 0.2667 0 180)
			(size 0.3048 0.381)
			(layers "F.Cu" "F.Mask" "F.Paste")
			(net "GND")
		)
	)
	(footprint ""
		(layer "F.Cu")
		(at 105.84561 -65.57391)
		(property "Reference" "R6218"
			(at 0 0 0)
			(layer "F.SilkS")
			(hide yes)
			(effects
				(font
					(size 1.27 1.27)
				)
			)
		)
		(property "Value" ""
			(at 0 0 0)
			(layer "F.Fab")
			(effects
				(font
					(size 1.27 1.27)
				)
			)
		)
		(duplicate_pad_numbers_are_jumpers no)
		(fp_line
			(start -0.7874 -0.4064)
			(end 0.7874 -0.4064)
			(stroke
				(width 0.1524)
				(type default)
			)
			(layer "F.SilkS")
		)
		(fp_line
			(start -0.7874 0.4064)
			(end -0.7874 -0.4064)
			(stroke
				(width 0.1524)
				(type default)
			)
			(layer "F.SilkS")
		)
		(fp_line
			(start 0.7874 -0.4064)
			(end 0.7874 0.4064)
			(stroke
				(width 0.1524)
				(type default)
			)
			(layer "F.SilkS")
		)
		(fp_line
			(start 0.7874 0.4064)
			(end -0.7874 0.4064)
			(stroke
				(width 0.1524)
				(type default)
			)
			(layer "F.SilkS")
		)
		(fp_line
			(start -0.67945 -0.305054)
			(end -0.12065 -0.305054)
			(stroke
				(width 0.1)
				(type default)
			)
			(layer "F.Fab")
		)
		(fp_line
			(start -0.67945 0.3048)
			(end -0.67945 -0.305054)
			(stroke
				(width 0.1)
				(type default)
			)
			(layer "F.Fab")
		)
		(fp_line
			(start -0.12065 -0.305054)
			(end -0.12065 -0.2794)
			(stroke
				(width 0.1)
				(type default)
			)
			(layer "F.Fab")
		)
		(fp_line
			(start -0.12065 -0.2794)
			(end 0.12065 -0.2794)
			(stroke
				(width 0.1)
				(type default)
			)
			(layer "F.Fab")
		)
		(fp_line
			(start -0.12065 0.2794)
			(end -0.12065 0.3048)
			(stroke
				(width 0.1)
				(type default)
			)
			(layer "F.Fab")
		)
		(fp_line
			(start -0.12065 0.3048)
			(end -0.67945 0.3048)
			(stroke
				(width 0.1)
				(type default)
			)
			(layer "F.Fab")
		)
		(fp_line
			(start 0.120396 0.2794)
			(end -0.12065 0.2794)
			(stroke
				(width 0.1)
				(type default)
			)
			(layer "F.Fab")
		)
		(fp_line
			(start 0.120396 0.3048)
			(end 0.120396 0.2794)
			(stroke
				(width 0.1)
				(type default)
			)
			(layer "F.Fab")
		)
		(fp_line
			(start 0.12065 -0.3048)
			(end 0.67945 -0.3048)
			(stroke
				(width 0.1)
				(type default)
			)
			(layer "F.Fab")
		)
		(fp_line
			(start 0.12065 -0.2794)
			(end 0.12065 -0.3048)
			(stroke
				(width 0.1)
				(type default)
			)
			(layer "F.Fab")
		)
		(fp_line
			(start 0.67945 -0.3048)
			(end 0.67945 0.3048)
			(stroke
				(width 0.1)
				(type default)
			)
			(layer "F.Fab")
		)
		(fp_line
			(start 0.67945 0.3048)
			(end 0.120396 0.3048)
			(stroke
				(width 0.1)
				(type default)
			)
			(layer "F.Fab")
		)
		(pad "1" smd circle
			(at -0.40005 0)
			(size 0 0)
			(layers "F.Cu" "F.Mask" "F.Paste")
			(net "P3V3_AUX")
		)
		(pad "2" smd circle
			(at 0.40005 0)
			(size 0 0)
			(layers "F.Cu" "F.Mask" "F.Paste")
			(net "USB_CPU0_ADD_A1")
		)
	)
	(footprint ""
		(layer "F.Cu")
		(at 69.493638 -386.44068 90)
		(property "Reference" "C117"
			(at 0 0 90)
			(layer "F.SilkS")
			(hide yes)
			(effects
				(font
					(size 1.27 1.27)
				)
			)
		)
		(property "Value" ""
			(at 0 0 90)
			(layer "F.Fab")
			(effects
				(font
					(size 1.27 1.27)
				)
			)
		)
		(duplicate_pad_numbers_are_jumpers no)
		(fp_line
			(start 0.7874 -0.4064)
			(end 0.7874 0.4064)
			(stroke
				(width 0.1524)
				(type default)
			)
			(layer "F.SilkS")
		)
		(fp_line
			(start -0.7874 -0.4064)
			(end 0.7874 -0.4064)
			(stroke
				(width 0.1524)
				(type default)
			)
			(layer "F.SilkS")
		)
		(fp_line
			(start 0.7874 0.4064)
			(end -0.7874 0.4064)
			(stroke
				(width 0.1524)
				(type default)
			)
			(layer "F.SilkS")
		)
		(fp_line
			(start -0.7874 0.4064)
			(end -0.7874 -0.4064)
			(stroke
				(width 0.1524)
				(type default)
			)
			(layer "F.SilkS")
		)
		(fp_line
			(start -0.12065 -0.305054)
			(end -0.12065 -0.2794)
			(stroke
				(width 0.1)
				(type default)
			)
			(layer "F.Fab")
		)
		(fp_line
			(start -0.67945 -0.305054)
			(end -0.12065 -0.305054)
			(stroke
				(width 0.1)
				(type default)
			)
			(layer "F.Fab")
		)
		(fp_line
			(start 0.67945 -0.3048)
			(end 0.67945 0.3048)
			(stroke
				(width 0.1)
				(type default)
			)
			(layer "F.Fab")
		)
		(fp_line
			(start 0.12065 -0.3048)
			(end 0.67945 -0.3048)
			(stroke
				(width 0.1)
				(type default)
			)
			(layer "F.Fab")
		)
		(fp_line
			(start 0.12065 -0.2794)
			(end 0.12065 -0.3048)
			(stroke
				(width 0.1)
				(type default)
			)
			(layer "F.Fab")
		)
		(fp_line
			(start -0.12065 -0.2794)
			(end 0.12065 -0.2794)
			(stroke
				(width 0.1)
				(type default)
			)
			(layer "F.Fab")
		)
		(fp_line
			(start 0.120396 0.2794)
			(end -0.12065 0.2794)
			(stroke
				(width 0.1)
				(type default)
			)
			(layer "F.Fab")
		)
		(fp_line
			(start -0.12065 0.2794)
			(end -0.12065 0.3048)
			(stroke
				(width 0.1)
				(type default)
			)
			(layer "F.Fab")
		)
		(fp_line
			(start 0.67945 0.3048)
			(end 0.120396 0.3048)
			(stroke
				(width 0.1)
				(type default)
			)
			(layer "F.Fab")
		)
		(fp_line
			(start 0.120396 0.3048)
			(end 0.120396 0.2794)
			(stroke
				(width 0.1)
				(type default)
			)
			(layer "F.Fab")
		)
		(fp_line
			(start -0.12065 0.3048)
			(end -0.67945 0.3048)
			(stroke
				(width 0.1)
				(type default)
			)
			(layer "F.Fab")
		)
		(fp_line
			(start -0.67945 0.3048)
			(end -0.67945 -0.305054)
			(stroke
				(width 0.1)
				(type default)
			)
			(layer "F.Fab")
		)
		(pad "1" smd circle
			(at -0.40005 0 90)
			(size 0 0)
			(layers "F.Cu" "F.Mask" "F.Paste")
			(net "P1V8_CPU1_RT0_1A")
		)
		(pad "2" smd circle
			(at 0.40005 0 90)
			(size 0 0)
			(layers "F.Cu" "F.Mask" "F.Paste")
			(net "GND")
		)
	)
)
